#ISCELL
  mstr_symbols cad_note *
  *
#ISCELL
  mstr_symbols intel_corp_bpage *
  *
#ISCELL
  mstr_symbols pvddq_abc *
  page98_i1
#ISCELL
  mstr_symbols pvddq_def *
  page98_i10
#ISCELL
  mstr_standard offpage *
  page98_i11
#CELL
  mstr_discrete res *
  page98_i12
#ISCELL
  mstr_symbols gnd *
  page98_i13
#CELL
  mstr_discrete res *
  page98_i14
#ISCELL
  mstr_standard offpage *
  page98_i16
#ISCELL
  mstr_standard offpage *
  page98_i3
#CELL
  dev_discrete cap_a *
  page98_i33
#CELL
  mstr_discrete res *
  page98_i36
#ISCELL
  mstr_symbols pvddq_abc *
  page98_i37
#CELL
  mstr_discrete res *
  page98_i38
#ISCELL
  mstr_standard offpage *
  page98_i39
#CELL
  mstr_discrete res *
  page98_i4
#CELL
  mstr_discrete res *
  page98_i40
#ISCELL
  mstr_symbols gnd *
  page98_i41
#CELL
  mstr_discrete res *
  page98_i42
#CELL
  dev_discrete cap_a *
  page98_i43
#ISCELL
  mstr_standard offpage *
  page98_i44
#ISCELL
  mstr_symbols pvddq_abc *
  page98_i45
#CELL
  mstr_discrete res *
  page98_i46
#ISCELL
  mstr_standard offpage *
  page98_i47
#CELL
  mstr_discrete res *
  page98_i48
#ISCELL
  mstr_symbols gnd *
  page98_i49
#CELL
  mstr_discrete res *
  page98_i5
#CELL
  mstr_discrete res *
  page98_i50
#CELL
  dev_discrete cap_a *
  page98_i51
#ISCELL
  mstr_standard offpage *
  page98_i52
#CELL
  mstr_discrete res *
  page98_i54
#ISCELL
  mstr_standard offpage *
  page98_i55
#CELL
  mstr_discrete res *
  page98_i56
#ISCELL
  mstr_symbols gnd *
  page98_i57
#CELL
  mstr_discrete res *
  page98_i58
#CELL
  dev_discrete cap_a *
  page98_i59
#ISCELL
  mstr_symbols gnd *
  page98_i6
#ISCELL
  mstr_standard offpage *
  page98_i60
#CELL
  mstr_discrete res *
  page98_i62
#ISCELL
  mstr_standard offpage *
  page98_i63
#CELL
  mstr_discrete res *
  page98_i64
#ISCELL
  mstr_symbols gnd *
  page98_i65
#CELL
  mstr_discrete res *
  page98_i66
#CELL
  dev_discrete cap_a *
  page98_i67
#ISCELL
  mstr_standard offpage *
  page98_i68
#ISCELL
  mstr_symbols pvddq_def *
  page98_i69
#CELL
  dev_discrete cap_a *
  page98_i7
#ISCELL
  mstr_symbols pvddq_def *
  page98_i70
#ISCELL
  mstr_standard offpage *
  page98_i8
#CELL
  mstr_discrete res *
  page98_i9
